(kicad_pcb
	(version 20260206)
	(generator "pcbnew")
	(generator_version "10.0")
	(general
		(thickness 1.6)
		(legacy_teardrops no)
	)
	(paper "A4")
	(title_block
		(title "Wiwynn_Tioga_Pass_MB.brd")
		(comment 1 "Tioga Pass / footprints 1317-1324 of 4770")
	)
	(layers
		(0 "F.Cu" signal "TOP")
		(4 "In1.Cu" signal "L2GND")
		(6 "In2.Cu" signal "L3")
		(8 "In3.Cu" signal "L4GND")
		(10 "In4.Cu" signal "L5")
		(12 "In5.Cu" signal "L6GND")
		(14 "In6.Cu" signal "L7VCC")
		(16 "In7.Cu" signal "L8VCC")
		(18 "In8.Cu" signal "L9GND")
		(20 "In9.Cu" signal "L10")
		(22 "In10.Cu" signal "L11GND")
		(24 "In11.Cu" signal "L12")
		(26 "In12.Cu" signal "L13GND")
		(2 "B.Cu" signal "BOTTOM")
		(9 "F.Adhes" user "F.Adhesive")
		(11 "B.Adhes" user "B.Adhesive")
		(13 "F.Paste" user "Package Geometry/Pastemask Top")
		(15 "B.Paste" user "Package Geometry/Pastemask Bottom")
		(5 "F.SilkS" user "Ref Des/Silkscreen Top")
		(7 "B.SilkS" user "Ref Des/Silkscreen Bottom")
		(1 "F.Mask" user "Board Geometry/Soldermask Top")
		(3 "B.Mask" user "Board Geometry/Soldermask Bottom")
		(17 "Dwgs.User" user "User.Drawings")
		(19 "Cmts.User" user "User.Comments")
		(21 "Eco1.User" user "User.Eco1")
		(23 "Eco2.User" user "User.Eco2")
		(25 "Edge.Cuts" user "Board Geometry/Outline")
		(27 "Margin" user)
		(31 "F.CrtYd" user "Package Geometry/Place Bound Top")
		(29 "B.CrtYd" user "Package Geometry/Place Bound Bottom")
		(35 "F.Fab" user "Ref Des/Assembly Top")
		(33 "B.Fab" user "Ref Des/Assembly Bottom")
	)
	(footprint ""
		(layer "F.Cu")
		(at 115.137692 -71.714614 180)
		(property "Reference" "C3D24"
			(at 0 0 180)
			(layer "F.SilkS")
			(hide yes)
			(effects
				(font
					(size 1.27 1.27)
				)
			)
		)
		(property "Value" ""
			(at 0 0 180)
			(layer "F.Fab")
			(effects
				(font
					(size 1.27 1.27)
				)
			)
		)
		(duplicate_pad_numbers_are_jumpers no)
		(fp_poly
			(pts
				(xy -0.4953 -0.2032) (xy 0.4953 -0.2032) (xy 0.4953 1.6002) (xy -0.4953 1.6002)
			)
			(stroke
				(width 0)
				(type default)
			)
			(fill no)
			(layer "F.CrtYd")
		)
		(fp_line
			(start 0.4953 1.6002)
			(end -0.4953 1.6002)
			(stroke
				(width 0.1)
				(type default)
			)
			(layer "F.Fab")
		)
		(fp_line
			(start 0.4953 -0.2032)
			(end 0.4953 1.6002)
			(stroke
				(width 0.1)
				(type default)
			)
			(layer "F.Fab")
		)
		(fp_line
			(start -0.4953 1.6002)
			(end -0.4953 -0.2032)
			(stroke
				(width 0.1)
				(type default)
			)
			(layer "F.Fab")
		)
		(fp_line
			(start -0.4953 -0.2032)
			(end 0.4953 -0.2032)
			(stroke
				(width 0.1)
				(type default)
			)
			(layer "F.Fab")
		)
		(pad "1" smd rect
			(at 0 0 180)
			(size 0.762 0.889)
			(layers "F.Cu" "F.Mask" "F.Paste")
			(net "PVCCIO_CPU1")
		)
		(pad "2" smd rect
			(at 0 1.397 180)
			(size 0.762 0.889)
			(layers "F.Cu" "F.Mask" "F.Paste")
			(net "GND")
		)
		(zone
			(layer "F.Cu")
			(hatch none 0.5)
			(connect_pads
				(clearance 0)
			)
			(min_thickness 0.25)
			(keepout
				(tracks not_allowed)
				(vias allowed)
				(pads allowed)
				(copperpour not_allowed)
				(footprints allowed)
			)
			(placement
				(enabled no)
				(sheetname "")
			)
			(fill
				(thermal_gap 0.5)
				(thermal_bridge_width 0.5)
				(island_removal_mode 0)
			)
			(polygon
				(pts
					(xy 115.518692 -72.159114) (xy 114.756692 -72.159114) (xy 114.756692 -72.667114) (xy 115.518692 -72.667114)
				)
			)
		)
	)
	(footprint ""
		(layer "F.Cu")
		(at 181.63413 -61.03112 180)
		(property "Reference" "C22W16"
			(at 0 0 180)
			(layer "F.SilkS")
			(hide yes)
			(effects
				(font
					(size 1.27 1.27)
				)
			)
		)
		(property "Value" "*"
			(at -0.0762 -6.2357 180)
			(unlocked yes)
			(layer "F.Fab")
			(hide yes)
			(effects
				(font
					(size 1.27 1.016)
					(thickness 0.1524)
				)
			)
		)
		(property "Device Type" "SC22U16V5MX-4-GP_SMD-BCG5-SC22A"
			(at -0.0762 -8.2677 180)
			(unlocked yes)
			(layer "F.Fab")
			(hide yes)
			(effects
				(font
					(size 1.27 1.016)
					(thickness 0.1524)
				)
			)
		)
		(duplicate_pad_numbers_are_jumpers no)
		(fp_line
			(start 0.635 0)
			(end -0.635 0)
			(stroke
				(width 0.508)
				(type default)
			)
			(layer "F.SilkS")
		)
		(fp_rect
			(start -0.9652 1.778)
			(end 0.9652 -1.778)
			(stroke
				(width 0)
				(type default)
			)
			(fill no)
			(layer "F.CrtYd")
		)
		(fp_poly
			(pts
				(xy -0.9652 -1.778) (xy 0.9652 -1.778) (xy 0.9652 1.778) (xy -0.9652 1.778)
			)
			(stroke
				(width 0)
				(type default)
			)
			(fill no)
			(layer "F.Fab")
		)
		(pad "1" smd rect
			(at 0 -0.9652 180)
			(size 1.397 1.143)
			(layers "F.Cu" "F.Mask" "F.Paste")
			(net "VR_FET_SW_P12V_STBY_PVCCIN_CPU0")
		)
		(pad "2" smd rect
			(at 0 0.9652 180)
			(size 1.397 1.143)
			(layers "F.Cu" "F.Mask" "F.Paste")
			(net "GND")
		)
	)
	(footprint ""
		(layer "F.Cu")
		(at 370.4463 -91.9353 180)
		(property "Reference" "R7C23"
			(at 0 0 180)
			(layer "F.SilkS")
			(hide yes)
			(effects
				(font
					(size 1.27 1.27)
				)
			)
		)
		(property "Value" ""
			(at 0 0 180)
			(layer "F.Fab")
			(effects
				(font
					(size 1.27 1.27)
				)
			)
		)
		(duplicate_pad_numbers_are_jumpers no)
		(fp_poly
			(pts
				(xy -0.2794 -0.1016) (xy 0.2794 -0.1016) (xy 0.2794 0.9906) (xy -0.2794 0.9906)
			)
			(stroke
				(width 0)
				(type default)
			)
			(fill no)
			(layer "F.CrtYd")
		)
		(fp_line
			(start 0.2794 0.9906)
			(end 0.2794 -0.1016)
			(stroke
				(width 0.1)
				(type default)
			)
			(layer "F.Fab")
		)
		(fp_line
			(start 0.2794 -0.1016)
			(end -0.2794 -0.1016)
			(stroke
				(width 0.1)
				(type default)
			)
			(layer "F.Fab")
		)
		(fp_line
			(start -0.2794 0.9906)
			(end 0.2794 0.9906)
			(stroke
				(width 0.1)
				(type default)
			)
			(layer "F.Fab")
		)
		(fp_line
			(start -0.2794 -0.1016)
			(end -0.2794 0.9906)
			(stroke
				(width 0.1)
				(type default)
			)
			(layer "F.Fab")
		)
		(pad "1" smd rect
			(at 0 0 180)
			(size 0.508 0.508)
			(layers "F.Cu" "F.Mask" "F.Paste")
			(net "P3V3_STBY")
		)
		(pad "2" smd rect
			(at 0 0.889 180)
			(size 0.508 0.508)
			(layers "F.Cu" "F.Mask" "F.Paste")
			(net "XDP_PCH_PWR_DEBUG_N")
		)
		(zone
			(layer "F.Cu")
			(hatch none 0.5)
			(connect_pads
				(clearance 0)
			)
			(min_thickness 0.25)
			(keepout
				(tracks not_allowed)
				(vias allowed)
				(pads allowed)
				(copperpour not_allowed)
				(footprints allowed)
			)
			(placement
				(enabled no)
				(sheetname "")
			)
			(fill
				(thermal_gap 0.5)
				(thermal_bridge_width 0.5)
				(island_removal_mode 0)
			)
			(polygon
				(pts
					(xy 370.7003 -92.5703) (xy 370.1923 -92.5703) (xy 370.1923 -92.1893) (xy 370.7003 -92.1893)
				)
			)
		)
		(zone
			(layer "F.Cu")
			(hatch none 0.5)
			(connect_pads
				(clearance 0)
			)
			(min_thickness 0.25)
			(keepout
				(tracks allowed)
				(vias not_allowed)
				(pads allowed)
				(copperpour not_allowed)
				(footprints allowed)
			)
			(placement
				(enabled no)
				(sheetname "")
			)
			(fill
				(thermal_gap 0.5)
				(thermal_bridge_width 0.5)
				(island_removal_mode 0)
			)
			(polygon
				(pts
					(xy 370.7003 -92.1893) (xy 370.1923 -92.1893) (xy 370.1923 -92.5703) (xy 370.7003 -92.5703)
				)
			)
		)
	)
	(footprint ""
		(layer "F.Cu")
		(at 431.622708 -127.587502 -90)
		(property "Reference" "C8B8"
			(at 0 0 270)
			(layer "F.SilkS")
			(hide yes)
			(effects
				(font
					(size 1.27 1.27)
				)
			)
		)
		(property "Value" ""
			(at 0 0 270)
			(layer "F.Fab")
			(effects
				(font
					(size 1.27 1.27)
				)
			)
		)
		(duplicate_pad_numbers_are_jumpers no)
		(fp_rect
			(start -0.3048 0.9906)
			(end 0.3048 -0.1016)
			(stroke
				(width 0)
				(type default)
			)
			(fill no)
			(layer "F.CrtYd")
		)
		(fp_line
			(start -0.3048 0.9906)
			(end 0.3048 0.9906)
			(stroke
				(width 0.1)
				(type default)
			)
			(layer "F.Fab")
		)
		(fp_line
			(start 0.3048 0.9906)
			(end 0.3048 -0.1016)
			(stroke
				(width 0.1)
				(type default)
			)
			(layer "F.Fab")
		)
		(fp_line
			(start -0.3048 -0.1016)
			(end -0.3048 0.9906)
			(stroke
				(width 0.1)
				(type default)
			)
			(layer "F.Fab")
		)
		(fp_line
			(start 0.3048 -0.1016)
			(end -0.3048 -0.1016)
			(stroke
				(width 0.1)
				(type default)
			)
			(layer "F.Fab")
		)
		(pad "1" smd rect
			(at 0 0 270)
			(size 0.508 0.508)
			(layers "F.Cu" "F.Mask" "F.Paste")
			(net "P5V_STBY")
		)
		(pad "2" smd rect
			(at 0 0.889 270)
			(size 0.508 0.508)
			(layers "F.Cu" "F.Mask" "F.Paste")
			(net "GND")
		)
		(zone
			(layer "F.Cu")
			(hatch none 0.5)
			(connect_pads
				(clearance 0)
			)
			(min_thickness 0.25)
			(keepout
				(tracks not_allowed)
				(vias allowed)
				(pads allowed)
				(copperpour not_allowed)
				(footprints allowed)
			)
			(placement
				(enabled no)
				(sheetname "")
			)
			(fill
				(thermal_gap 0.5)
				(thermal_bridge_width 0.5)
				(island_removal_mode 0)
			)
			(polygon
				(pts
					(xy 430.987708 -127.841502) (xy 430.987708 -127.333502) (xy 431.368708 -127.333502) (xy 431.368708 -127.841502)
				)
			)
		)
		(zone
			(layer "F.Cu")
			(hatch none 0.5)
			(connect_pads
				(clearance 0)
			)
			(min_thickness 0.25)
			(keepout
				(tracks allowed)
				(vias not_allowed)
				(pads allowed)
				(copperpour not_allowed)
				(footprints allowed)
			)
			(placement
				(enabled no)
				(sheetname "")
			)
			(fill
				(thermal_gap 0.5)
				(thermal_bridge_width 0.5)
				(island_removal_mode 0)
			)
			(polygon
				(pts
					(xy 430.987708 -127.841502) (xy 430.987708 -127.333502) (xy 431.368708 -127.333502) (xy 431.368708 -127.841502)
				)
			)
		)
	)
	(footprint ""
		(layer "F.Cu")
		(at 23.057612 -68.796408 90)
		(property "Reference" "R1W20"
			(at -0.8382 -0.67818 90)
			(unlocked yes)
			(layer "F.SilkS")
			(effects
				(font
					(size 0.4064 0.254)
					(thickness 0.1524)
				)
				(justify left)
			)
		)
		(property "Value" ""
			(at 0 0 90)
			(layer "F.Fab")
			(effects
				(font
					(size 1.27 1.27)
				)
			)
		)
		(duplicate_pad_numbers_are_jumpers no)
		(fp_poly
			(pts
				(xy -0.2794 -0.1016) (xy 0.2794 -0.1016) (xy 0.2794 0.9906) (xy -0.2794 0.9906)
			)
			(stroke
				(width 0)
				(type default)
			)
			(fill no)
			(layer "F.CrtYd")
		)
		(fp_line
			(start 0.2794 -0.1016)
			(end -0.2794 -0.1016)
			(stroke
				(width 0.1)
				(type default)
			)
			(layer "F.Fab")
		)
		(fp_line
			(start -0.2794 -0.1016)
			(end -0.2794 0.9906)
			(stroke
				(width 0.1)
				(type default)
			)
			(layer "F.Fab")
		)
		(fp_line
			(start 0.2794 0.9906)
			(end 0.2794 -0.1016)
			(stroke
				(width 0.1)
				(type default)
			)
			(layer "F.Fab")
		)
		(fp_line
			(start -0.2794 0.9906)
			(end 0.2794 0.9906)
			(stroke
				(width 0.1)
				(type default)
			)
			(layer "F.Fab")
		)
		(pad "1" smd rect
			(at 0 0 90)
			(size 0.508 0.508)
			(layers "F.Cu" "F.Mask" "F.Paste")
			(net "A_HSC_TEMP")
		)
		(pad "2" smd rect
			(at 0 0.889 90)
			(size 0.508 0.508)
			(layers "F.Cu" "F.Mask" "F.Paste")
			(net "TEMP_SENSOR_B")
		)
		(zone
			(layer "F.Cu")
			(hatch none 0.5)
			(connect_pads
				(clearance 0)
			)
			(min_thickness 0.25)
			(keepout
				(tracks allowed)
				(vias not_allowed)
				(pads allowed)
				(copperpour not_allowed)
				(footprints allowed)
			)
			(placement
				(enabled no)
				(sheetname "")
			)
			(fill
				(thermal_gap 0.5)
				(thermal_bridge_width 0.5)
				(island_removal_mode 0)
			)
			(polygon
				(pts
					(xy 23.311612 -68.542408) (xy 23.311612 -69.050408) (xy 23.692612 -69.050408) (xy 23.692612 -68.542408)
				)
			)
		)
		(zone
			(layer "F.Cu")
			(hatch none 0.5)
			(connect_pads
				(clearance 0)
			)
			(min_thickness 0.25)
			(keepout
				(tracks not_allowed)
				(vias allowed)
				(pads allowed)
				(copperpour not_allowed)
				(footprints allowed)
			)
			(placement
				(enabled no)
				(sheetname "")
			)
			(fill
				(thermal_gap 0.5)
				(thermal_bridge_width 0.5)
				(island_removal_mode 0)
			)
			(polygon
				(pts
					(xy 23.692612 -68.542408) (xy 23.692612 -69.050408) (xy 23.311612 -69.050408) (xy 23.311612 -68.542408)
				)
			)
		)
	)
	(footprint ""
		(layer "F.Cu")
		(at 183.3626 -136.4234 180)
		(property "Reference" "C4A19"
			(at 0 0 180)
			(layer "F.SilkS")
			(hide yes)
			(effects
				(font
					(size 1.27 1.27)
				)
			)
		)
		(property "Value" ""
			(at 0 0 180)
			(layer "F.Fab")
			(effects
				(font
					(size 1.27 1.27)
				)
			)
		)
		(duplicate_pad_numbers_are_jumpers no)
		(fp_poly
			(pts
				(xy -0.7239 -0.2159) (xy 0.7239 -0.2159) (xy 0.7239 1.9939) (xy -0.7239 1.9939)
			)
			(stroke
				(width 0)
				(type default)
			)
			(fill no)
			(layer "F.CrtYd")
		)
		(fp_line
			(start 0.7239 1.9939)
			(end 0.7239 -0.2159)
			(stroke
				(width 0.1)
				(type default)
			)
			(layer "F.Fab")
		)
		(fp_line
			(start 0.7239 -0.2159)
			(end -0.7239 -0.2159)
			(stroke
				(width 0.1)
				(type default)
			)
			(layer "F.Fab")
		)
		(fp_line
			(start -0.7239 1.9939)
			(end 0.7239 1.9939)
			(stroke
				(width 0.1)
				(type default)
			)
			(layer "F.Fab")
		)
		(fp_line
			(start -0.7239 -0.2159)
			(end -0.7239 1.9939)
			(stroke
				(width 0.1)
				(type default)
			)
			(layer "F.Fab")
		)
		(pad "1" smd rect
			(at 0 0 180)
			(size 1.27 1.016)
			(layers "F.Cu" "F.Mask" "F.Paste")
			(net "VR_FET_SW_P12V_STBY_PVPP_KLM")
		)
		(pad "2" smd rect
			(at 0 1.778 180)
			(size 1.27 1.016)
			(layers "F.Cu" "F.Mask" "F.Paste")
			(net "GND")
		)
		(zone
			(layer "F.Cu")
			(hatch none 0.5)
			(connect_pads
				(clearance 0)
			)
			(min_thickness 0.25)
			(keepout
				(tracks not_allowed)
				(vias allowed)
				(pads allowed)
				(copperpour not_allowed)
				(footprints allowed)
			)
			(placement
				(enabled no)
				(sheetname "")
			)
			(fill
				(thermal_gap 0.5)
				(thermal_bridge_width 0.5)
				(island_removal_mode 0)
			)
			(polygon
				(pts
					(xy 183.9976 -136.9314) (xy 182.7276 -136.9314) (xy 182.7276 -137.6934) (xy 183.9976 -137.6934)
				)
			)
		)
	)
	(footprint ""
		(layer "F.Cu")
		(at 430.972468 -50.482246 -90)
		(property "Reference" "R9F61"
			(at 0 0 270)
			(layer "F.SilkS")
			(hide yes)
			(effects
				(font
					(size 1.27 1.27)
				)
			)
		)
		(property "Value" ""
			(at 0 0 270)
			(layer "F.Fab")
			(effects
				(font
					(size 1.27 1.27)
				)
			)
		)
		(duplicate_pad_numbers_are_jumpers no)
		(fp_poly
			(pts
				(xy -0.2794 -0.1016) (xy 0.2794 -0.1016) (xy 0.2794 0.9906) (xy -0.2794 0.9906)
			)
			(stroke
				(width 0)
				(type default)
			)
			(fill no)
			(layer "F.CrtYd")
		)
		(fp_line
			(start -0.2794 0.9906)
			(end 0.2794 0.9906)
			(stroke
				(width 0.1)
				(type default)
			)
			(layer "F.Fab")
		)
		(fp_line
			(start 0.2794 0.9906)
			(end 0.2794 -0.1016)
			(stroke
				(width 0.1)
				(type default)
			)
			(layer "F.Fab")
		)
		(fp_line
			(start -0.2794 -0.1016)
			(end -0.2794 0.9906)
			(stroke
				(width 0.1)
				(type default)
			)
			(layer "F.Fab")
		)
		(fp_line
			(start 0.2794 -0.1016)
			(end -0.2794 -0.1016)
			(stroke
				(width 0.1)
				(type default)
			)
			(layer "F.Fab")
		)
		(pad "1" smd rect
			(at 0 0 270)
			(size 0.508 0.508)
			(layers "F.Cu" "F.Mask" "F.Paste")
			(net "P3V3_STBY")
		)
		(pad "2" smd rect
			(at 0 0.889 270)
			(size 0.508 0.508)
			(layers "F.Cu" "F.Mask" "F.Paste")
			(net "PU_24M_OSC_OE")
		)
		(zone
			(layer "F.Cu")
			(hatch none 0.5)
			(connect_pads
				(clearance 0)
			)
			(min_thickness 0.25)
			(keepout
				(tracks not_allowed)
				(vias allowed)
				(pads allowed)
				(copperpour not_allowed)
				(footprints allowed)
			)
			(placement
				(enabled no)
				(sheetname "")
			)
			(fill
				(thermal_gap 0.5)
				(thermal_bridge_width 0.5)
				(island_removal_mode 0)
			)
			(polygon
				(pts
					(xy 430.337468 -50.736246) (xy 430.337468 -50.228246) (xy 430.718468 -50.228246) (xy 430.718468 -50.736246)
				)
			)
		)
		(zone
			(layer "F.Cu")
			(hatch none 0.5)
			(connect_pads
				(clearance 0)
			)
			(min_thickness 0.25)
			(keepout
				(tracks allowed)
				(vias not_allowed)
				(pads allowed)
				(copperpour not_allowed)
				(footprints allowed)
			)
			(placement
				(enabled no)
				(sheetname "")
			)
			(fill
				(thermal_gap 0.5)
				(thermal_bridge_width 0.5)
				(island_removal_mode 0)
			)
			(polygon
				(pts
					(xy 430.718468 -50.736246) (xy 430.718468 -50.228246) (xy 430.337468 -50.228246) (xy 430.337468 -50.736246)
				)
			)
		)
	)
	(footprint ""
		(layer "F.Cu")
		(at 287.168082 12.01039 -90)
		(property "Reference" "T1P14"
			(at 0 0 270)
			(layer "F.SilkS")
			(hide yes)
			(effects
				(font
					(size 1.27 1.27)
				)
			)
		)
		(property "Value" "*"
			(at -3.302 1.12395 270)
			(unlocked yes)
			(layer "F.Fab")
			(hide yes)
			(effects
				(font
					(size 0.889 0.889)
					(thickness 0.1524)
				)
			)
		)
		(property "Device Type" "TPAD-DIFF-4P-GP_DISCRET-GB3-TPA"
			(at -3.302 -0.40005 270)
			(unlocked yes)
			(layer "F.Fab")
			(hide yes)
			(effects
				(font
					(size 0.889 0.889)
					(thickness 0.1524)
				)
			)
		)
		(duplicate_pad_numbers_are_jumpers no)
		(fp_line
			(start -2.286 2.286)
			(end 2.286 2.286)
			(stroke
				(width 0.1524)
				(type default)
			)
			(layer "F.SilkS")
		)
		(fp_line
			(start 2.286 2.286)
			(end 2.286 -2.286)
			(stroke
				(width 0.1524)
				(type default)
			)
			(layer "F.SilkS")
		)
		(fp_line
			(start -2.286 -2.286)
			(end -2.286 2.286)
			(stroke
				(width 0.1524)
				(type default)
			)
			(layer "F.SilkS")
		)
		(fp_line
			(start 2.286 -2.286)
			(end -2.286 -2.286)
			(stroke
				(width 0.1524)
				(type default)
			)
			(layer "F.SilkS")
		)
		(fp_line
			(start -2.413 -2.413)
			(end -2.413 -1.143)
			(stroke
				(width 0.4064)
				(type default)
			)
			(layer "F.SilkS")
		)
		(fp_line
			(start -1.143 -2.413)
			(end -2.413 -2.413)
			(stroke
				(width 0.4064)
				(type default)
			)
			(layer "F.SilkS")
		)
		(fp_rect
			(start -2.54 2.54)
			(end 2.54 -2.54)
			(stroke
				(width 0)
				(type default)
			)
			(fill no)
			(layer "F.CrtYd")
		)
		(fp_rect
			(start -2.54 2.54)
			(end 2.54 -2.54)
			(stroke
				(width 0)
				(type default)
			)
			(fill no)
			(layer "F.Fab")
		)
		(pad "1" thru_hole circle
			(at -1.27 -1.27 270)
			(size 1.524 1.524)
			(drill 0.9144)
			(layers "*.Cu" "*.Mask")
			(remove_unused_layers no)
			(net "L1_95OHM_6INCH_DP")
			(clearance -0.0508)
			(thermal_gap 0.127)
			(padstack
				(mode front_inner_back)
				(layer "Inner"
					(shape circle)
					(size 1.1684 1.1684)
					(clearance 0.127)
				)
				(layer "B.Cu"
					(shape circle)
					(size 1.524 1.524)
					(clearance -0.0508)
				)
			)
		)
		(pad "2" thru_hole circle
			(at 1.27 -1.27 270)
			(size 1.524 1.524)
			(drill 0.9144)
			(layers "*.Cu" "*.Mask")
			(remove_unused_layers no)
			(net "L1_95OHM_6INCH_DN")
			(clearance -0.0508)
			(thermal_gap 0.127)
			(padstack
				(mode front_inner_back)
				(layer "Inner"
					(shape circle)
					(size 1.1684 1.1684)
					(clearance 0.127)
				)
				(layer "B.Cu"
					(shape circle)
					(size 1.524 1.524)
					(clearance -0.0508)
				)
			)
		)
		(pad "GND1" thru_hole rect
			(at -1.27 1.27 270)
			(size 1.524 1.524)
			(drill 0.9144)
			(layers "*.Cu" "*.Mask")
			(remove_unused_layers no)
			(net "GND")
			(clearance -0.0508)
			(thermal_gap 0.127)
			(padstack
				(mode front_inner_back)
				(layer "Inner"
					(shape circle)
					(size 1.1684 1.1684)
					(clearance 0.127)
				)
				(layer "B.Cu"
					(shape rect)
					(size 1.524 1.524)
					(clearance -0.0508)
				)
			)
		)
		(pad "GND2" thru_hole rect
			(at 1.27 1.27 270)
			(size 1.524 1.524)
			(drill 0.9144)
			(layers "*.Cu" "*.Mask")
			(remove_unused_layers no)
			(net "GND")
			(clearance -0.0508)
			(thermal_gap 0.127)
			(padstack
				(mode front_inner_back)
				(layer "Inner"
					(shape circle)
					(size 1.1684 1.1684)
					(clearance 0.127)
				)
				(layer "B.Cu"
					(shape rect)
					(size 1.524 1.524)
					(clearance -0.0508)
				)
			)
		)
	)
)
